FILE_TYPE = MACRO_DRAWING;
SET COLOR_WIRE YELLOW;
SET COLOR_PROP ORANGE;
SET COLOR_DOT WHITE;
SET COLOR_ARC YELLOW;
SET COLOR_BODY GREEN;
SET COLOR_NOTE PURPLE;
SET PROP_DISPLAY VALUE;
SET PAGE_NUMBER P113;
FORCEADD QUANTA_TITLE_BLOCK_C..1
(0 0);
FORCEPROP 1 LAST CUSTOM_TXT_CDS <NAME_2>
J 0
(-3175 50);
FORCEPROP 1 LAST CUSTOM_TXT_CDS <NAME_1>
J 0
(-3175 175);
FORCEPROP 1 LAST CUSTOM_TXT_CDS <Q_NUMBER>
J 0
(-1403 103);
DISPLAY 1.212766 (-1403 103);
FORCEPROP 1 LAST CUSTOM_TXT_CDS <Q_PROJ>
J 0
(-2382 102);
DISPLAY 1.212766 (-2382 102);
FORCEPROP 1 LAST CUSTOM_TXT_CDS <Q_REV>
J 0
(-184 103);
DISPLAY 1.212766 (-184 103);
FORCEPROP 1 LAST CUSTOM_TXT_CDS <CON_LAST_MODIFIED>
J 0
(-1885 15);
DISPLAY 0.978723 (-1885 15);
FORCEPROP 1 LAST CUSTOM_TXT_CDS <CON_PAGE_NUM> OF <CON_TOTAL_PAGES>
J 0
(-446 18);
DISPLAY 0.978723 (-446 18);
FORCEPROP 1 LAST Q_DEPT BU9
J 1
(-3763 49);
DISPLAY 1.957447 (-3763 49);
PAINT GREEN (-3763 49);
FORCEPROP 1 LAST Q_TITLE Blank
J 0
(-9300 50);
DISPLAY 2.446809 (-9300 50);
PAINT GREEN (-9300 50);
FORCEPROP 0 LAST CDS_CON_LAST_MODIFIED Wed Jul 21 11:36:07 2021
J 0
(-1885 15);
DISPLAY INVISIBLE (-1885 15);
FORCEPROP 2 LAST PAGE_BORDER TRUE
J 0
(-7890 5250);
DISPLAY 0.638298 (-7890 5250);
PAINT PINK (-7890 5250);
DISPLAY INVISIBLE (-7890 5250);
FORCEPROP 1 LAST CDS_LMAN_SYM_OUTLINE -9475,6775,100,-125
J 0
(0 0);
DISPLAY 0.468085 (0 0);
PAINT GREEN (0 0);
DISPLAY INVISIBLE (0 0);
FORCEPROP 2 LAST CDS_LIB pure_quanta
J 0
(0 0);
DISPLAY INVISIBLE (0 0);
FORCEPROP 1 LAST COMMENT_BODY TRUE
J 0
(12 -13);
DISPLAY 0.978723 (12 -13);
PAINT GREEN (12 -13);
DISPLAY INVISIBLE (12 -13);
FORCEPROP 2 LAST CUSTOM_TXT_CDS <XR_PAGE_TITLE>
J 0
(-7890 5250);
DISPLAY 0.638298 (-7890 5250);
PAINT PINK (-7890 5250);
DISPLAY INVISIBLE (-7890 5250);
FORCEPROP 2 LAST CDS_XR_PAGE_TITLE CR-113 : @T6G_MB_LIB.T6G(SCH_1):PAGE113
J 0
(-7890 5250);
DISPLAY 0.638298 (-7890 5250);
PAINT PINK (-7890 5250);
DISPLAY INVISIBLE (-7890 5250);
QUIT
